# BASEBOARD_FAB2 (Tioga Pass) — schematic netlist excerpt (pin names and nets, part order shuffled) for the footprints in the layout excerpt that follows; sources: Cadence DE-HDL packaged netlist, KiCad conversion of Wiwynn_Tioga_Pass_MB.brd

C5P8  CAP  22UF 4V 20% X6S  pkg 0805LF  page 42 : A = PVSA_CPU0 ; B = GND
C4D14  SC1U10V2KX-4-GP  10%  pkg SMD-BCG6  page 203 : \1\ = P5V_STBY ; \2\ = GND
R7D44  RES  4.75K 1% CHIP  pkg 0402  page 133 : A = P1V05_PCH_STBY ; B = FM_OCP_MEZZB_PRES_1V05_PCH_N

(kicad_pcb
	(version 20260206)
	(generator "pcbnew")
	(generator_version "10.0")
	(general
		(thickness 1.6)
		(legacy_teardrops no)
	)
	(paper "A4")
	(title_block
		(title "Wiwynn_Tioga_Pass_MB.brd")
		(comment 1 "Tioga Pass / footprints 4016-4018 of 4770")
	)
	(layers
		(0 "F.Cu" signal "TOP")
		(4 "In1.Cu" signal "L2GND")
		(6 "In2.Cu" signal "L3")
		(8 "In3.Cu" signal "L4GND")
		(10 "In4.Cu" signal "L5")
		(12 "In5.Cu" signal "L6GND")
		(14 "In6.Cu" signal "L7VCC")
		(16 "In7.Cu" signal "L8VCC")
		(18 "In8.Cu" signal "L9GND")
		(20 "In9.Cu" signal "L10")
		(22 "In10.Cu" signal "L11GND")
		(24 "In11.Cu" signal "L12")
		(26 "In12.Cu" signal "L13GND")
		(2 "B.Cu" signal "BOTTOM")
		(9 "F.Adhes" user "F.Adhesive")
		(11 "B.Adhes" user "B.Adhesive")
		(13 "F.Paste" user "Package Geometry/Pastemask Top")
		(15 "B.Paste" user "Package Geometry/Pastemask Bottom")
		(5 "F.SilkS" user "Ref Des/Silkscreen Top")
		(7 "B.SilkS" user "Ref Des/Silkscreen Bottom")
		(1 "F.Mask" user "Board Geometry/Soldermask Top")
		(3 "B.Mask" user "Board Geometry/Soldermask Bottom")
		(17 "Dwgs.User" user "User.Drawings")
		(19 "Cmts.User" user "User.Comments")
		(21 "Eco1.User" user "User.Eco1")
		(23 "Eco2.User" user "User.Eco2")
		(25 "Edge.Cuts" user "Board Geometry/Outline")
		(27 "Margin" user)
		(31 "F.CrtYd" user "Package Geometry/Place Bound Top")
		(29 "B.CrtYd" user "Package Geometry/Place Bound Bottom")
		(35 "F.Fab" user "Ref Des/Assembly Top")
		(33 "B.Fab" user "Ref Des/Assembly Bottom")
	)
	(footprint ""
		(layer "B.Cu")
		(at 260.923024 -82.001614)
		(property "Reference" "C5P8"
			(at 0 0 0)
			(layer "B.SilkS")
			(hide yes)
			(effects
				(font
					(size 1.27 1.27)
				)
				(justify mirror)
			)
		)
		(property "Value" ""
			(at 0 0 0)
			(layer "B.Fab")
			(effects
				(font
					(size 1.27 1.27)
				)
				(justify mirror)
			)
		)
		(duplicate_pad_numbers_are_jumpers no)
		(fp_poly
			(pts
				(xy 0.7239 -0.2159) (xy -0.7239 -0.2159) (xy -0.7239 1.9939) (xy 0.7239 1.9939)
			)
			(stroke
				(width 0)
				(type default)
			)
			(fill no)
			(layer "B.CrtYd")
		)
		(fp_line
			(start -0.7239 -0.2159)
			(end 0.7239 -0.2159)
			(stroke
				(width 0.1)
				(type default)
			)
			(layer "B.Fab")
		)
		(fp_line
			(start -0.7239 1.9939)
			(end -0.7239 -0.2159)
			(stroke
				(width 0.1)
				(type default)
			)
			(layer "B.Fab")
		)
		(fp_line
			(start 0.7239 -0.2159)
			(end 0.7239 1.9939)
			(stroke
				(width 0.1)
				(type default)
			)
			(layer "B.Fab")
		)
		(fp_line
			(start 0.7239 1.9939)
			(end -0.7239 1.9939)
			(stroke
				(width 0.1)
				(type default)
			)
			(layer "B.Fab")
		)
		(pad "1" smd rect
			(at 0 0 180)
			(size 1.27 1.016)
			(layers "B.Cu" "B.Mask" "B.Paste")
			(net "PVSA_CPU0")
		)
		(pad "2" smd rect
			(at 0 1.778 180)
			(size 1.27 1.016)
			(layers "B.Cu" "B.Mask" "B.Paste")
			(net "GND")
		)
		(zone
			(layer "B.Cu")
			(hatch none 0.5)
			(connect_pads
				(clearance 0)
			)
			(min_thickness 0.25)
			(keepout
				(tracks not_allowed)
				(vias allowed)
				(pads allowed)
				(copperpour not_allowed)
				(footprints allowed)
			)
			(placement
				(enabled no)
				(sheetname "")
			)
			(fill
				(thermal_gap 0.5)
				(thermal_bridge_width 0.5)
				(island_removal_mode 0)
			)
			(polygon
				(pts
					(xy 261.558024 -81.493614) (xy 260.288024 -81.493614) (xy 260.288024 -80.731614) (xy 261.558024 -80.731614)
				)
			)
		)
	)
	(footprint ""
		(layer "B.Cu")
		(at 385.813808 -84.729828 180)
		(property "Reference" "R7D44"
			(at 0.8382 -0.67818 180)
			(unlocked yes)
			(layer "B.SilkS")
			(effects
				(font
					(size 0.4064 0.254)
					(thickness 0.1524)
				)
				(justify left mirror)
			)
		)
		(property "Value" ""
			(at 0 0 0)
			(layer "B.Fab")
			(effects
				(font
					(size 1.27 1.27)
				)
				(justify mirror)
			)
		)
		(duplicate_pad_numbers_are_jumpers no)
		(fp_poly
			(pts
				(xy 0.2794 -0.1016) (xy -0.2794 -0.1016) (xy -0.2794 0.9906) (xy 0.2794 0.9906)
			)
			(stroke
				(width 0)
				(type default)
			)
			(fill no)
			(layer "B.CrtYd")
		)
		(fp_line
			(start 0.2794 0.9906)
			(end -0.2794 0.9906)
			(stroke
				(width 0.1)
				(type default)
			)
			(layer "B.Fab")
		)
		(fp_line
			(start 0.2794 -0.1016)
			(end 0.2794 0.9906)
			(stroke
				(width 0.1)
				(type default)
			)
			(layer "B.Fab")
		)
		(fp_line
			(start -0.2794 0.9906)
			(end -0.2794 -0.1016)
			(stroke
				(width 0.1)
				(type default)
			)
			(layer "B.Fab")
		)
		(fp_line
			(start -0.2794 -0.1016)
			(end 0.2794 -0.1016)
			(stroke
				(width 0.1)
				(type default)
			)
			(layer "B.Fab")
		)
		(pad "1" smd rect
			(at 0 0)
			(size 0.508 0.508)
			(layers "B.Cu" "B.Mask" "B.Paste")
			(net "P1V05_PCH_STBY")
		)
		(pad "2" smd rect
			(at 0 0.889)
			(size 0.508 0.508)
			(layers "B.Cu" "B.Mask" "B.Paste")
			(net "FM_OCP_MEZZB_PRES_1V05_PCH_N")
		)
		(zone
			(layer "B.Cu")
			(hatch none 0.5)
			(connect_pads
				(clearance 0)
			)
			(min_thickness 0.25)
			(keepout
				(tracks not_allowed)
				(vias allowed)
				(pads allowed)
				(copperpour not_allowed)
				(footprints allowed)
			)
			(placement
				(enabled no)
				(sheetname "")
			)
			(fill
				(thermal_gap 0.5)
				(thermal_bridge_width 0.5)
				(island_removal_mode 0)
			)
			(polygon
				(pts
					(xy 385.559808 -85.364828) (xy 386.067808 -85.364828) (xy 386.067808 -84.983828) (xy 385.559808 -84.983828)
				)
			)
		)
		(zone
			(layer "B.Cu")
			(hatch none 0.5)
			(connect_pads
				(clearance 0)
			)
			(min_thickness 0.25)
			(keepout
				(tracks allowed)
				(vias not_allowed)
				(pads allowed)
				(copperpour not_allowed)
				(footprints allowed)
			)
			(placement
				(enabled no)
				(sheetname "")
			)
			(fill
				(thermal_gap 0.5)
				(thermal_bridge_width 0.5)
				(island_removal_mode 0)
			)
			(polygon
				(pts
					(xy 385.559808 -84.983828) (xy 386.067808 -84.983828) (xy 386.067808 -85.364828) (xy 385.559808 -85.364828)
				)
			)
		)
	)
	(footprint ""
		(layer "B.Cu")
		(at 198.623428 -69.477382 90)
		(property "Reference" "C4D14"
			(at 0 0 90)
			(layer "B.SilkS")
			(hide yes)
			(effects
				(font
					(size 1.27 1.27)
				)
				(justify mirror)
			)
		)
		(property "Value" "*"
			(at -1.1811 -2.8194 90)
			(unlocked yes)
			(layer "B.Fab")
			(hide yes)
			(effects
				(font
					(size 1.27 1.016)
					(thickness 0.1524)
				)
				(justify mirror)
			)
		)
		(property "Device Type" "SC1U10V2KX-4-GP_SMD-BCG6-SC1U1A"
			(at -1.1811 -4.3434 90)
			(unlocked yes)
			(layer "B.Fab")
			(hide yes)
			(effects
				(font
					(size 1.27 1.016)
					(thickness 0.1524)
				)
				(justify mirror)
			)
		)
		(duplicate_pad_numbers_are_jumpers no)
		(fp_rect
			(start 0.4318 0.9525)
			(end -0.4318 -0.9525)
			(stroke
				(width 0)
				(type default)
			)
			(fill no)
			(layer "B.CrtYd")
		)
		(fp_rect
			(start 0.4318 0.9525)
			(end -0.4318 -0.9525)
			(stroke
				(width 0)
				(type default)
			)
			(fill no)
			(layer "B.Fab")
		)
		(pad "1" smd custom
			(at 0 -0.4445 270)
			(size 0.1524 0.1524)
			(layers "B.Cu" "B.Mask" "B.Paste")
			(net "P5V_STBY")
			(options
				(clearance outline)
				(anchor circle)
			)
			(primitives
				(gr_poly
					(pts
						(arc
							(start 0.3048 0.2032)
							(mid 0.275042 0.275042)
							(end 0.2032 0.3048)
						)
						(arc
							(start -0.2032 0.3048)
							(mid -0.275042 0.275042)
							(end -0.3048 0.2032)
						)
						(arc
							(start -0.3048 -0.2032)
							(mid -0.275042 -0.275042)
							(end -0.2032 -0.3048)
						)
						(arc
							(start 0.2032 -0.3048)
							(mid 0.275042 -0.275042)
							(end 0.3048 -0.2032)
						)
					)
					(width 0)
					(fill yes)
				)
			)
		)
		(pad "2" smd custom
			(at 0 0.4445 270)
			(size 0.1524 0.1524)
			(layers "B.Cu" "B.Mask" "B.Paste")
			(net "GND")
			(options
				(clearance outline)
				(anchor circle)
			)
			(primitives
				(gr_poly
					(pts
						(arc
							(start 0.3048 0.2032)
							(mid 0.275042 0.275042)
							(end 0.2032 0.3048)
						)
						(arc
							(start -0.2032 0.3048)
							(mid -0.275042 0.275042)
							(end -0.3048 0.2032)
						)
						(arc
							(start -0.3048 -0.2032)
							(mid -0.275042 -0.275042)
							(end -0.2032 -0.3048)
						)
						(arc
							(start 0.2032 -0.3048)
							(mid 0.275042 -0.275042)
							(end 0.3048 -0.2032)
						)
					)
					(width 0)
					(fill yes)
				)
			)
		)
	)
)
